(kicad_pcb
	(version 20260206)
	(generator "pcbnew")
	(generator_version "10.0")
	(general
		(thickness 1.6)
		(legacy_teardrops no)
	)
	(paper "A4")
	(title_block
		(title "03242023_DA0F0TMBIJ0_F0T_Motherboard_J_brd_V01_OCP.brd")
		(comment 1 "Grand Teton / footprints 2642-2649 of 6105")
	)
	(layers
		(0 "F.Cu" signal "TOP")
		(4 "In1.Cu" signal "GND")
		(6 "In2.Cu" signal "IN1")
		(8 "In3.Cu" signal "GND1")
		(10 "In4.Cu" signal "IN2")
		(12 "In5.Cu" signal "GND2")
		(14 "In6.Cu" signal "IN3")
		(16 "In7.Cu" signal "GND3")
		(18 "In8.Cu" signal "VCC")
		(20 "In9.Cu" signal "VCC1")
		(22 "In10.Cu" signal "GND4")
		(24 "In11.Cu" signal "IN4")
		(26 "In12.Cu" signal "GND5")
		(28 "In13.Cu" signal "IN5")
		(30 "In14.Cu" signal "GND6")
		(32 "In15.Cu" signal "IN6")
		(34 "In16.Cu" signal "GND7")
		(2 "B.Cu" signal "BOTTOM")
		(9 "F.Adhes" user "F.Adhesive")
		(11 "B.Adhes" user "B.Adhesive")
		(13 "F.Paste" user "Package Geometry/Pastemask Top")
		(15 "B.Paste" user "Package Geometry/Pastemask Bottom")
		(5 "F.SilkS" user "Ref Des/Silkscreen Top")
		(7 "B.SilkS" user "Ref Des/Silkscreen Bottom")
		(1 "F.Mask" user "Board Geometry/Soldermask Top")
		(3 "B.Mask" user "Board Geometry/Soldermask Bottom")
		(17 "Dwgs.User" user "User.Drawings")
		(19 "Cmts.User" user "User.Comments")
		(21 "Eco1.User" user "User.Eco1")
		(23 "Eco2.User" user "User.Eco2")
		(25 "Edge.Cuts" user "Board Geometry/Outline")
		(27 "Margin" user)
		(31 "F.CrtYd" user "Package Geometry/Place Bound Top")
		(29 "B.CrtYd" user "Package Geometry/Place Bound Bottom")
		(35 "F.Fab" user "Ref Des/Assembly Top")
		(33 "B.Fab" user "Ref Des/Assembly Bottom")
	)
	(footprint ""
		(layer "F.Cu")
		(at 428.179992 -401.655534)
		(property "Reference" "Q106"
			(at -1.071372 -3.402584 0)
			(unlocked yes)
			(layer "F.SilkS")
			(effects
				(font
					(size 0.7874 0.5842)
					(thickness 0.1524)
				)
				(justify left)
			)
		)
		(property "Value" ""
			(at 0 0 0)
			(layer "F.Fab")
			(effects
				(font
					(size 1.27 1.27)
				)
			)
		)
		(duplicate_pad_numbers_are_jumpers no)
		(fp_line
			(start -1.332738 -1.100074)
			(end -0.4826 -1.100074)
			(stroke
				(width 0.1524)
				(type default)
			)
			(layer "F.SilkS")
		)
		(fp_line
			(start -1.332738 1.100074)
			(end -1.332738 -1.100074)
			(stroke
				(width 0.1524)
				(type default)
			)
			(layer "F.SilkS")
		)
		(fp_line
			(start -0.4826 -1.100074)
			(end 0 -0.541274)
			(stroke
				(width 0.1524)
				(type default)
			)
			(layer "F.SilkS")
		)
		(fp_line
			(start 0 -0.541274)
			(end 0.4826 -1.100074)
			(stroke
				(width 0.1524)
				(type default)
			)
			(layer "F.SilkS")
		)
		(fp_line
			(start 0.4826 -1.100074)
			(end 1.332738 -1.100074)
			(stroke
				(width 0.1524)
				(type default)
			)
			(layer "F.SilkS")
		)
		(fp_line
			(start 1.332738 -1.100074)
			(end 1.332738 1.100074)
			(stroke
				(width 0.1524)
				(type default)
			)
			(layer "F.SilkS")
		)
		(fp_line
			(start 1.332738 1.100074)
			(end -1.332738 1.100074)
			(stroke
				(width 0.1524)
				(type default)
			)
			(layer "F.SilkS")
		)
		(fp_poly
			(pts
				(xy -0.672592 -2.035302) (xy -1.02362 -1.333246) (xy -1.374648 -2.035302)
			)
			(stroke
				(width 0)
				(type default)
			)
			(fill yes)
			(layer "F.SilkS")
		)
		(fp_line
			(start -0.674878 -1.100074)
			(end 0.674878 -1.100074)
			(stroke
				(width 0.1)
				(type default)
			)
			(layer "F.Fab")
		)
		(fp_line
			(start -0.674878 1.100074)
			(end -0.674878 -1.100074)
			(stroke
				(width 0.1)
				(type default)
			)
			(layer "F.Fab")
		)
		(fp_line
			(start 0.674878 -1.100074)
			(end 0.674878 1.100074)
			(stroke
				(width 0.1)
				(type default)
			)
			(layer "F.Fab")
		)
		(fp_line
			(start 0.674878 1.100074)
			(end -0.674878 1.100074)
			(stroke
				(width 0.1)
				(type default)
			)
			(layer "F.Fab")
		)
		(fp_poly
			(pts
				(xy -2.2352 -0.298958) (xy -2.2352 -1.001014) (xy -1.533144 -0.649986)
			)
			(stroke
				(width 0)
				(type default)
			)
			(fill yes)
			(layer "F.Fab")
		)
		(pad "1" smd rect
			(at -0.94996 -0.649986 90)
			(size 0.4318 0.508)
			(layers "F.Cu" "F.Mask" "F.Paste")
			(net "GND")
		)
		(pad "2" smd rect
			(at -0.94996 0 90)
			(size 0.4318 0.508)
			(layers "F.Cu" "F.Mask" "F.Paste")
			(net "GPU_WP_HW_CTRL_N")
		)
		(pad "3" smd rect
			(at -0.94996 0.649986 90)
			(size 0.4318 0.508)
			(layers "F.Cu" "F.Mask" "F.Paste")
			(net "Net_27")
		)
		(pad "4" smd rect
			(at 0.94996 0.649986 90)
			(size 0.4318 0.508)
			(layers "F.Cu" "F.Mask" "F.Paste")
			(net "Net_25")
		)
		(pad "5" smd rect
			(at 0.94996 0 90)
			(size 0.4318 0.508)
			(layers "F.Cu" "F.Mask" "F.Paste")
			(net "Net_26")
		)
		(pad "6" smd rect
			(at 0.94996 -0.649986 90)
			(size 0.4318 0.508)
			(layers "F.Cu" "F.Mask" "F.Paste")
			(net "GPU_WP_HW_CTRL_ISO")
		)
	)
	(footprint ""
		(layer "F.Cu")
		(at 412.56585 -408.517344 -90)
		(property "Reference" "C896"
			(at 0 0 270)
			(layer "F.SilkS")
			(hide yes)
			(effects
				(font
					(size 1.27 1.27)
				)
			)
		)
		(property "Value" ""
			(at 0 0 270)
			(layer "F.Fab")
			(effects
				(font
					(size 1.27 1.27)
				)
			)
		)
		(duplicate_pad_numbers_are_jumpers no)
		(fp_line
			(start -0.299974 0.150114)
			(end -0.299974 -0.150114)
			(stroke
				(width 0.1)
				(type default)
			)
			(layer "F.Fab")
		)
		(fp_line
			(start 0.299974 0.150114)
			(end -0.299974 0.150114)
			(stroke
				(width 0.1)
				(type default)
			)
			(layer "F.Fab")
		)
		(fp_line
			(start -0.299974 -0.150114)
			(end 0.299974 -0.150114)
			(stroke
				(width 0.1)
				(type default)
			)
			(layer "F.Fab")
		)
		(fp_line
			(start 0.299974 -0.150114)
			(end 0.299974 0.150114)
			(stroke
				(width 0.1)
				(type default)
			)
			(layer "F.Fab")
		)
		(pad "1" smd rect
			(at -0.2667 0 270)
			(size 0.3048 0.381)
			(layers "F.Cu" "F.Mask" "F.Paste")
			(net "P5E_CPU0_PE3_TX_C_DN<2>")
		)
		(pad "2" smd rect
			(at 0.2667 0 270)
			(size 0.3048 0.381)
			(layers "F.Cu" "F.Mask" "F.Paste")
			(net "P5E_CPU0_PE3_TX_DN<2>")
		)
	)
	(footprint ""
		(layer "F.Cu")
		(at 135.445754 -402.371052 -90)
		(property "Reference" "C753"
			(at 0 0 270)
			(layer "F.SilkS")
			(hide yes)
			(effects
				(font
					(size 1.27 1.27)
				)
			)
		)
		(property "Value" ""
			(at 0 0 270)
			(layer "F.Fab")
			(effects
				(font
					(size 1.27 1.27)
				)
			)
		)
		(duplicate_pad_numbers_are_jumpers no)
		(fp_line
			(start -0.299974 0.150114)
			(end -0.299974 -0.150114)
			(stroke
				(width 0.1)
				(type default)
			)
			(layer "F.Fab")
		)
		(fp_line
			(start 0.299974 0.150114)
			(end -0.299974 0.150114)
			(stroke
				(width 0.1)
				(type default)
			)
			(layer "F.Fab")
		)
		(fp_line
			(start -0.299974 -0.150114)
			(end 0.299974 -0.150114)
			(stroke
				(width 0.1)
				(type default)
			)
			(layer "F.Fab")
		)
		(fp_line
			(start 0.299974 -0.150114)
			(end 0.299974 0.150114)
			(stroke
				(width 0.1)
				(type default)
			)
			(layer "F.Fab")
		)
		(pad "1" smd rect
			(at -0.2667 0 270)
			(size 0.3048 0.381)
			(layers "F.Cu" "F.Mask" "F.Paste")
			(net "P5E_CPU1_PE2_TX_C_DP<10>")
		)
		(pad "2" smd rect
			(at 0.2667 0 270)
			(size 0.3048 0.381)
			(layers "F.Cu" "F.Mask" "F.Paste")
			(net "P5E_CPU1_PE2_TX_DP<10>")
		)
	)
	(footprint ""
		(layer "F.Cu")
		(at 155.171394 -408.517344 -90)
		(property "Reference" "C1538"
			(at 0 0 270)
			(layer "F.SilkS")
			(hide yes)
			(effects
				(font
					(size 1.27 1.27)
				)
			)
		)
		(property "Value" ""
			(at 0 0 270)
			(layer "F.Fab")
			(effects
				(font
					(size 1.27 1.27)
				)
			)
		)
		(duplicate_pad_numbers_are_jumpers no)
		(fp_line
			(start -0.299974 0.150114)
			(end -0.299974 -0.150114)
			(stroke
				(width 0.1)
				(type default)
			)
			(layer "F.Fab")
		)
		(fp_line
			(start 0.299974 0.150114)
			(end -0.299974 0.150114)
			(stroke
				(width 0.1)
				(type default)
			)
			(layer "F.Fab")
		)
		(fp_line
			(start -0.299974 -0.150114)
			(end 0.299974 -0.150114)
			(stroke
				(width 0.1)
				(type default)
			)
			(layer "F.Fab")
		)
		(fp_line
			(start 0.299974 -0.150114)
			(end 0.299974 0.150114)
			(stroke
				(width 0.1)
				(type default)
			)
			(layer "F.Fab")
		)
		(pad "1" smd rect
			(at -0.2667 0 270)
			(size 0.3048 0.381)
			(layers "F.Cu" "F.Mask" "F.Paste")
			(net "P5E_CPU1_PE3_TX_C_DN<4>")
		)
		(pad "2" smd rect
			(at 0.2667 0 270)
			(size 0.3048 0.381)
			(layers "F.Cu" "F.Mask" "F.Paste")
			(net "P5E_CPU1_PE3_TX_DN<4>")
		)
	)
	(footprint ""
		(layer "F.Cu")
		(at 174.87138 -99.863148 -90)
		(property "Reference" "R124"
			(at 0 0 270)
			(layer "F.SilkS")
			(hide yes)
			(effects
				(font
					(size 1.27 1.27)
				)
			)
		)
		(property "Value" ""
			(at 0 0 270)
			(layer "F.Fab")
			(effects
				(font
					(size 1.27 1.27)
				)
			)
		)
		(duplicate_pad_numbers_are_jumpers no)
		(fp_line
			(start -0.7874 0.4064)
			(end -0.7874 -0.4064)
			(stroke
				(width 0.1524)
				(type default)
			)
			(layer "F.SilkS")
		)
		(fp_line
			(start 0.7874 0.4064)
			(end -0.7874 0.4064)
			(stroke
				(width 0.1524)
				(type default)
			)
			(layer "F.SilkS")
		)
		(fp_line
			(start -0.7874 -0.4064)
			(end 0.7874 -0.4064)
			(stroke
				(width 0.1524)
				(type default)
			)
			(layer "F.SilkS")
		)
		(fp_line
			(start 0.7874 -0.4064)
			(end 0.7874 0.4064)
			(stroke
				(width 0.1524)
				(type default)
			)
			(layer "F.SilkS")
		)
		(fp_line
			(start -0.67945 0.3048)
			(end -0.67945 -0.305054)
			(stroke
				(width 0.1)
				(type default)
			)
			(layer "F.Fab")
		)
		(fp_line
			(start -0.12065 0.3048)
			(end -0.67945 0.3048)
			(stroke
				(width 0.1)
				(type default)
			)
			(layer "F.Fab")
		)
		(fp_line
			(start 0.120396 0.3048)
			(end 0.120396 0.2794)
			(stroke
				(width 0.1)
				(type default)
			)
			(layer "F.Fab")
		)
		(fp_line
			(start 0.67945 0.3048)
			(end 0.120396 0.3048)
			(stroke
				(width 0.1)
				(type default)
			)
			(layer "F.Fab")
		)
		(fp_line
			(start -0.12065 0.2794)
			(end -0.12065 0.3048)
			(stroke
				(width 0.1)
				(type default)
			)
			(layer "F.Fab")
		)
		(fp_line
			(start 0.120396 0.2794)
			(end -0.12065 0.2794)
			(stroke
				(width 0.1)
				(type default)
			)
			(layer "F.Fab")
		)
		(fp_line
			(start -0.12065 -0.2794)
			(end 0.12065 -0.2794)
			(stroke
				(width 0.1)
				(type default)
			)
			(layer "F.Fab")
		)
		(fp_line
			(start 0.12065 -0.2794)
			(end 0.12065 -0.3048)
			(stroke
				(width 0.1)
				(type default)
			)
			(layer "F.Fab")
		)
		(fp_line
			(start 0.12065 -0.3048)
			(end 0.67945 -0.3048)
			(stroke
				(width 0.1)
				(type default)
			)
			(layer "F.Fab")
		)
		(fp_line
			(start 0.67945 -0.3048)
			(end 0.67945 0.3048)
			(stroke
				(width 0.1)
				(type default)
			)
			(layer "F.Fab")
		)
		(fp_line
			(start -0.67945 -0.305054)
			(end -0.12065 -0.305054)
			(stroke
				(width 0.1)
				(type default)
			)
			(layer "F.Fab")
		)
		(fp_line
			(start -0.12065 -0.305054)
			(end -0.12065 -0.2794)
			(stroke
				(width 0.1)
				(type default)
			)
			(layer "F.Fab")
		)
		(pad "1" smd circle
			(at -0.40005 0 270)
			(size 0 0)
			(layers "F.Cu" "F.Mask" "F.Paste")
			(net "PWRGD_DRAMPWRGD_CPU1_CD_R_LVC1")
		)
		(pad "2" smd circle
			(at 0.40005 0 270)
			(size 0 0)
			(layers "F.Cu" "F.Mask" "F.Paste")
			(net "PWRGD_DRAMPWRGD_CPU1_CD_LVC1_R2")
		)
	)
	(footprint ""
		(layer "F.Cu")
		(at 376.468132 -80.354424)
		(property "Reference" "PC1238"
			(at 0 0 0)
			(layer "F.SilkS")
			(hide yes)
			(effects
				(font
					(size 1.27 1.27)
				)
			)
		)
		(property "Value" ""
			(at 0 0 0)
			(layer "F.Fab")
			(effects
				(font
					(size 1.27 1.27)
				)
			)
		)
		(duplicate_pad_numbers_are_jumpers no)
		(fp_line
			(start -1.524 -0.762)
			(end 1.524 -0.762)
			(stroke
				(width 0.1524)
				(type default)
			)
			(layer "F.SilkS")
		)
		(fp_line
			(start -1.524 0.762)
			(end -1.524 -0.762)
			(stroke
				(width 0.1524)
				(type default)
			)
			(layer "F.SilkS")
		)
		(fp_line
			(start 1.524 -0.762)
			(end 1.524 0.762)
			(stroke
				(width 0.1524)
				(type default)
			)
			(layer "F.SilkS")
		)
		(fp_line
			(start 1.524 0.762)
			(end -1.524 0.762)
			(stroke
				(width 0.1524)
				(type default)
			)
			(layer "F.SilkS")
		)
		(fp_line
			(start -1.1049 -0.724916)
			(end -1.1049 0.724916)
			(stroke
				(width 0.1)
				(type default)
			)
			(layer "F.Fab")
		)
		(fp_line
			(start -1.1049 0.724916)
			(end 1.1049 0.724916)
			(stroke
				(width 0.1)
				(type default)
			)
			(layer "F.Fab")
		)
		(fp_line
			(start 1.1049 -0.724916)
			(end -1.1049 -0.724916)
			(stroke
				(width 0.1)
				(type default)
			)
			(layer "F.Fab")
		)
		(fp_line
			(start 1.1049 0.724916)
			(end 1.1049 -0.724916)
			(stroke
				(width 0.1)
				(type default)
			)
			(layer "F.Fab")
		)
		(pad "1" smd rect
			(at -0.889 0 180)
			(size 1.016 1.27)
			(layers "F.Cu" "F.Mask" "F.Paste")
			(net "P1V8_PCH_AUX")
		)
		(pad "2" smd rect
			(at 0.889 0 180)
			(size 1.016 1.27)
			(layers "F.Cu" "F.Mask" "F.Paste")
			(net "GND")
		)
	)
	(footprint ""
		(layer "F.Cu")
		(at 159.82188 -59.527948 180)
		(property "Reference" "C1305"
			(at 0 0 180)
			(layer "F.SilkS")
			(hide yes)
			(effects
				(font
					(size 1.27 1.27)
				)
			)
		)
		(property "Value" ""
			(at 0 0 180)
			(layer "F.Fab")
			(effects
				(font
					(size 1.27 1.27)
				)
			)
		)
		(duplicate_pad_numbers_are_jumpers no)
		(fp_line
			(start 0.7874 0.4064)
			(end -0.7874 0.4064)
			(stroke
				(width 0.1524)
				(type default)
			)
			(layer "F.SilkS")
		)
		(fp_line
			(start 0.7874 -0.4064)
			(end 0.7874 0.4064)
			(stroke
				(width 0.1524)
				(type default)
			)
			(layer "F.SilkS")
		)
		(fp_line
			(start -0.7874 0.4064)
			(end -0.7874 -0.4064)
			(stroke
				(width 0.1524)
				(type default)
			)
			(layer "F.SilkS")
		)
		(fp_line
			(start -0.7874 -0.4064)
			(end 0.7874 -0.4064)
			(stroke
				(width 0.1524)
				(type default)
			)
			(layer "F.SilkS")
		)
		(fp_line
			(start 0.67945 0.3048)
			(end 0.120396 0.3048)
			(stroke
				(width 0.1)
				(type default)
			)
			(layer "F.Fab")
		)
		(fp_line
			(start 0.67945 -0.3048)
			(end 0.67945 0.3048)
			(stroke
				(width 0.1)
				(type default)
			)
			(layer "F.Fab")
		)
		(fp_line
			(start 0.12065 -0.2794)
			(end 0.12065 -0.3048)
			(stroke
				(width 0.1)
				(type default)
			)
			(layer "F.Fab")
		)
		(fp_line
			(start 0.12065 -0.3048)
			(end 0.67945 -0.3048)
			(stroke
				(width 0.1)
				(type default)
			)
			(layer "F.Fab")
		)
		(fp_line
			(start 0.120396 0.3048)
			(end 0.120396 0.2794)
			(stroke
				(width 0.1)
				(type default)
			)
			(layer "F.Fab")
		)
		(fp_line
			(start 0.120396 0.2794)
			(end -0.12065 0.2794)
			(stroke
				(width 0.1)
				(type default)
			)
			(layer "F.Fab")
		)
		(fp_line
			(start -0.12065 0.3048)
			(end -0.67945 0.3048)
			(stroke
				(width 0.1)
				(type default)
			)
			(layer "F.Fab")
		)
		(fp_line
			(start -0.12065 0.2794)
			(end -0.12065 0.3048)
			(stroke
				(width 0.1)
				(type default)
			)
			(layer "F.Fab")
		)
		(fp_line
			(start -0.12065 -0.2794)
			(end 0.12065 -0.2794)
			(stroke
				(width 0.1)
				(type default)
			)
			(layer "F.Fab")
		)
		(fp_line
			(start -0.12065 -0.305054)
			(end -0.12065 -0.2794)
			(stroke
				(width 0.1)
				(type default)
			)
			(layer "F.Fab")
		)
		(fp_line
			(start -0.67945 0.3048)
			(end -0.67945 -0.305054)
			(stroke
				(width 0.1)
				(type default)
			)
			(layer "F.Fab")
		)
		(fp_line
			(start -0.67945 -0.305054)
			(end -0.12065 -0.305054)
			(stroke
				(width 0.1)
				(type default)
			)
			(layer "F.Fab")
		)
		(pad "1" smd circle
			(at -0.40005 0 180)
			(size 0 0)
			(layers "F.Cu" "F.Mask" "F.Paste")
			(net "P3V3_AUX")
		)
		(pad "2" smd circle
			(at 0.40005 0 180)
			(size 0 0)
			(layers "F.Cu" "F.Mask" "F.Paste")
			(net "GND")
		)
	)
	(footprint ""
		(layer "F.Cu")
		(at 432.061112 -397.270478 180)
		(property "Reference" "R3435"
			(at 0 0 180)
			(layer "F.SilkS")
			(hide yes)
			(effects
				(font
					(size 1.27 1.27)
				)
			)
		)
		(property "Value" ""
			(at 0 0 180)
			(layer "F.Fab")
			(effects
				(font
					(size 1.27 1.27)
				)
			)
		)
		(duplicate_pad_numbers_are_jumpers no)
		(fp_line
			(start 0.7874 0.4064)
			(end -0.7874 0.4064)
			(stroke
				(width 0.1524)
				(type default)
			)
			(layer "F.SilkS")
		)
		(fp_line
			(start 0.7874 -0.4064)
			(end 0.7874 0.4064)
			(stroke
				(width 0.1524)
				(type default)
			)
			(layer "F.SilkS")
		)
		(fp_line
			(start -0.7874 0.4064)
			(end -0.7874 -0.4064)
			(stroke
				(width 0.1524)
				(type default)
			)
			(layer "F.SilkS")
		)
		(fp_line
			(start -0.7874 -0.4064)
			(end 0.7874 -0.4064)
			(stroke
				(width 0.1524)
				(type default)
			)
			(layer "F.SilkS")
		)
		(fp_line
			(start 0.67945 0.3048)
			(end 0.120396 0.3048)
			(stroke
				(width 0.1)
				(type default)
			)
			(layer "F.Fab")
		)
		(fp_line
			(start 0.67945 -0.3048)
			(end 0.67945 0.3048)
			(stroke
				(width 0.1)
				(type default)
			)
			(layer "F.Fab")
		)
		(fp_line
			(start 0.12065 -0.2794)
			(end 0.12065 -0.3048)
			(stroke
				(width 0.1)
				(type default)
			)
			(layer "F.Fab")
		)
		(fp_line
			(start 0.12065 -0.3048)
			(end 0.67945 -0.3048)
			(stroke
				(width 0.1)
				(type default)
			)
			(layer "F.Fab")
		)
		(fp_line
			(start 0.120396 0.3048)
			(end 0.120396 0.2794)
			(stroke
				(width 0.1)
				(type default)
			)
			(layer "F.Fab")
		)
		(fp_line
			(start 0.120396 0.2794)
			(end -0.12065 0.2794)
			(stroke
				(width 0.1)
				(type default)
			)
			(layer "F.Fab")
		)
		(fp_line
			(start -0.12065 0.3048)
			(end -0.67945 0.3048)
			(stroke
				(width 0.1)
				(type default)
			)
			(layer "F.Fab")
		)
		(fp_line
			(start -0.12065 0.2794)
			(end -0.12065 0.3048)
			(stroke
				(width 0.1)
				(type default)
			)
			(layer "F.Fab")
		)
		(fp_line
			(start -0.12065 -0.2794)
			(end 0.12065 -0.2794)
			(stroke
				(width 0.1)
				(type default)
			)
			(layer "F.Fab")
		)
		(fp_line
			(start -0.12065 -0.305054)
			(end -0.12065 -0.2794)
			(stroke
				(width 0.1)
				(type default)
			)
			(layer "F.Fab")
		)
		(fp_line
			(start -0.67945 0.3048)
			(end -0.67945 -0.305054)
			(stroke
				(width 0.1)
				(type default)
			)
			(layer "F.Fab")
		)
		(fp_line
			(start -0.67945 -0.305054)
			(end -0.12065 -0.305054)
			(stroke
				(width 0.1)
				(type default)
			)
			(layer "F.Fab")
		)
		(pad "1" smd circle
			(at -0.40005 0 180)
			(size 0 0)
			(layers "F.Cu" "F.Mask" "F.Paste")
			(net "P3V3_AUX")
		)
		(pad "2" smd circle
			(at 0.40005 0 180)
			(size 0 0)
			(layers "F.Cu" "F.Mask" "F.Paste")
			(net "GPU_FPGA_OVERT")
		)
	)
)
